# BASEBOARD_FAB2 (Tioga Pass) — schematic netlist excerpt (pin names and nets, part order shuffled) for the footprints in the layout excerpt that follows; sources: Cadence DE-HDL packaged netlist, KiCad conversion of Wiwynn_Tioga_Pass_MB.brd

C2U4  CAP  0.22UF 16V 10% X7R  pkg 0402  page 107 : A = P3E_CPU0_PE1_PCH_RXN<0> ; B = P3E_CPU0_PE1_SS_RXN<0>
R24W2  RES  3.3K 5% CHIP  pkg 0402  page 138 : A = P3V3_STBY ; B = SMB_SLOTX24_PCH_STBY_LVC3_SCL
C9P22  CAP  10UF 16V 10% X6S  pkg 0805  page 207 : A = VR_FET_SW_P12V_STBY_PVCCIN_CPU1 ; B = GND

(kicad_pcb
	(version 20260206)
	(generator "pcbnew")
	(generator_version "10.0")
	(general
		(thickness 1.6)
		(legacy_teardrops no)
	)
	(paper "A4")
	(title_block
		(title "Wiwynn_Tioga_Pass_MB.brd")
		(comment 1 "Tioga Pass / footprints 3331-3333 of 4770")
	)
	(layers
		(0 "F.Cu" signal "TOP")
		(4 "In1.Cu" signal "L2GND")
		(6 "In2.Cu" signal "L3")
		(8 "In3.Cu" signal "L4GND")
		(10 "In4.Cu" signal "L5")
		(12 "In5.Cu" signal "L6GND")
		(14 "In6.Cu" signal "L7VCC")
		(16 "In7.Cu" signal "L8VCC")
		(18 "In8.Cu" signal "L9GND")
		(20 "In9.Cu" signal "L10")
		(22 "In10.Cu" signal "L11GND")
		(24 "In11.Cu" signal "L12")
		(26 "In12.Cu" signal "L13GND")
		(2 "B.Cu" signal "BOTTOM")
		(9 "F.Adhes" user "F.Adhesive")
		(11 "B.Adhes" user "B.Adhesive")
		(13 "F.Paste" user "Package Geometry/Pastemask Top")
		(15 "B.Paste" user "Package Geometry/Pastemask Bottom")
		(5 "F.SilkS" user "Ref Des/Silkscreen Top")
		(7 "B.SilkS" user "Ref Des/Silkscreen Bottom")
		(1 "F.Mask" user "Board Geometry/Soldermask Top")
		(3 "B.Mask" user "Board Geometry/Soldermask Bottom")
		(17 "Dwgs.User" user "User.Drawings")
		(19 "Cmts.User" user "User.Comments")
		(21 "Eco1.User" user "User.Eco1")
		(23 "Eco2.User" user "User.Eco2")
		(25 "Edge.Cuts" user "Board Geometry/Outline")
		(27 "Margin" user)
		(31 "F.CrtYd" user "Package Geometry/Place Bound Top")
		(29 "B.CrtYd" user "Package Geometry/Place Bound Bottom")
		(35 "F.Fab" user "Ref Des/Assembly Top")
		(33 "B.Fab" user "Ref Des/Assembly Bottom")
	)
	(footprint ""
		(layer "B.Cu")
		(at 32.832802 -68.101464 90)
		(property "Reference" "C9P22"
			(at 0 0 90)
			(layer "B.SilkS")
			(hide yes)
			(effects
				(font
					(size 1.27 1.27)
				)
				(justify mirror)
			)
		)
		(property "Value" ""
			(at 0 0 90)
			(layer "B.Fab")
			(effects
				(font
					(size 1.27 1.27)
				)
				(justify mirror)
			)
		)
		(duplicate_pad_numbers_are_jumpers no)
		(fp_poly
			(pts
				(xy 0.7239 -0.2159) (xy -0.7239 -0.2159) (xy -0.7239 1.9939) (xy 0.7239 1.9939)
			)
			(stroke
				(width 0)
				(type default)
			)
			(fill no)
			(layer "B.CrtYd")
		)
		(fp_line
			(start 0.7239 -0.2159)
			(end 0.7239 1.9939)
			(stroke
				(width 0.1)
				(type default)
			)
			(layer "B.Fab")
		)
		(fp_line
			(start -0.7239 -0.2159)
			(end 0.7239 -0.2159)
			(stroke
				(width 0.1)
				(type default)
			)
			(layer "B.Fab")
		)
		(fp_line
			(start 0.7239 1.9939)
			(end -0.7239 1.9939)
			(stroke
				(width 0.1)
				(type default)
			)
			(layer "B.Fab")
		)
		(fp_line
			(start -0.7239 1.9939)
			(end -0.7239 -0.2159)
			(stroke
				(width 0.1)
				(type default)
			)
			(layer "B.Fab")
		)
		(pad "1" smd rect
			(at 0 0 270)
			(size 1.27 1.016)
			(layers "B.Cu" "B.Mask" "B.Paste")
			(net "VR_FET_SW_P12V_STBY_PVCCIN_CPU1")
		)
		(pad "2" smd rect
			(at 0 1.778 270)
			(size 1.27 1.016)
			(layers "B.Cu" "B.Mask" "B.Paste")
			(net "GND")
		)
		(zone
			(layer "B.Cu")
			(hatch none 0.5)
			(connect_pads
				(clearance 0)
			)
			(min_thickness 0.25)
			(keepout
				(tracks not_allowed)
				(vias allowed)
				(pads allowed)
				(copperpour not_allowed)
				(footprints allowed)
			)
			(placement
				(enabled no)
				(sheetname "")
			)
			(fill
				(thermal_gap 0.5)
				(thermal_bridge_width 0.5)
				(island_removal_mode 0)
			)
			(polygon
				(pts
					(xy 33.340802 -68.736464) (xy 33.340802 -67.466464) (xy 34.102802 -67.466464) (xy 34.102802 -68.736464)
				)
			)
		)
	)
	(footprint ""
		(layer "B.Cu")
		(at 400.756628 -115.579144)
		(property "Reference" "R24W2"
			(at 0.8382 -0.67818 0)
			(unlocked yes)
			(layer "B.SilkS")
			(effects
				(font
					(size 0.4064 0.254)
					(thickness 0.1524)
				)
				(justify left mirror)
			)
		)
		(property "Value" ""
			(at 0 0 0)
			(layer "B.Fab")
			(effects
				(font
					(size 1.27 1.27)
				)
				(justify mirror)
			)
		)
		(duplicate_pad_numbers_are_jumpers no)
		(fp_poly
			(pts
				(xy 0.2794 -0.1016) (xy -0.2794 -0.1016) (xy -0.2794 0.9906) (xy 0.2794 0.9906)
			)
			(stroke
				(width 0)
				(type default)
			)
			(fill no)
			(layer "B.CrtYd")
		)
		(fp_line
			(start -0.2794 -0.1016)
			(end 0.2794 -0.1016)
			(stroke
				(width 0.1)
				(type default)
			)
			(layer "B.Fab")
		)
		(fp_line
			(start -0.2794 0.9906)
			(end -0.2794 -0.1016)
			(stroke
				(width 0.1)
				(type default)
			)
			(layer "B.Fab")
		)
		(fp_line
			(start 0.2794 -0.1016)
			(end 0.2794 0.9906)
			(stroke
				(width 0.1)
				(type default)
			)
			(layer "B.Fab")
		)
		(fp_line
			(start 0.2794 0.9906)
			(end -0.2794 0.9906)
			(stroke
				(width 0.1)
				(type default)
			)
			(layer "B.Fab")
		)
		(pad "1" smd rect
			(at 0 0 180)
			(size 0.508 0.508)
			(layers "B.Cu" "B.Mask" "B.Paste")
			(net "P3V3_STBY")
		)
		(pad "2" smd rect
			(at 0 0.889 180)
			(size 0.508 0.508)
			(layers "B.Cu" "B.Mask" "B.Paste")
			(net "SMB_SLOTX24_PCH_STBY_LVC3_SCL")
		)
		(zone
			(layer "B.Cu")
			(hatch none 0.5)
			(connect_pads
				(clearance 0)
			)
			(min_thickness 0.25)
			(keepout
				(tracks allowed)
				(vias not_allowed)
				(pads allowed)
				(copperpour not_allowed)
				(footprints allowed)
			)
			(placement
				(enabled no)
				(sheetname "")
			)
			(fill
				(thermal_gap 0.5)
				(thermal_bridge_width 0.5)
				(island_removal_mode 0)
			)
			(polygon
				(pts
					(xy 401.010628 -115.325144) (xy 400.502628 -115.325144) (xy 400.502628 -114.944144) (xy 401.010628 -114.944144)
				)
			)
		)
		(zone
			(layer "B.Cu")
			(hatch none 0.5)
			(connect_pads
				(clearance 0)
			)
			(min_thickness 0.25)
			(keepout
				(tracks not_allowed)
				(vias allowed)
				(pads allowed)
				(copperpour not_allowed)
				(footprints allowed)
			)
			(placement
				(enabled no)
				(sheetname "")
			)
			(fill
				(thermal_gap 0.5)
				(thermal_bridge_width 0.5)
				(island_removal_mode 0)
			)
			(polygon
				(pts
					(xy 401.010628 -114.944144) (xy 400.502628 -114.944144) (xy 400.502628 -115.325144) (xy 401.010628 -115.325144)
				)
			)
		)
	)
	(footprint ""
		(layer "B.Cu")
		(at 334.743806 -61.257434)
		(property "Reference" "C2U4"
			(at 0 0 0)
			(layer "B.SilkS")
			(hide yes)
			(effects
				(font
					(size 1.27 1.27)
				)
				(justify mirror)
			)
		)
		(property "Value" ""
			(at 0 0 0)
			(layer "B.Fab")
			(effects
				(font
					(size 1.27 1.27)
				)
				(justify mirror)
			)
		)
		(duplicate_pad_numbers_are_jumpers no)
		(fp_poly
			(pts
				(xy -0.3048 -0.1016) (xy -0.3048 0.9906) (xy 0.3048 0.9906) (xy 0.3048 -0.1016)
			)
			(stroke
				(width 0)
				(type default)
			)
			(fill no)
			(layer "B.CrtYd")
		)
		(fp_line
			(start -0.3048 -0.1016)
			(end 0.3048 -0.1016)
			(stroke
				(width 0.1)
				(type default)
			)
			(layer "B.Fab")
		)
		(fp_line
			(start -0.3048 0.9906)
			(end -0.3048 -0.1016)
			(stroke
				(width 0.1)
				(type default)
			)
			(layer "B.Fab")
		)
		(fp_line
			(start 0.3048 -0.1016)
			(end 0.3048 0.9906)
			(stroke
				(width 0.1)
				(type default)
			)
			(layer "B.Fab")
		)
		(fp_line
			(start 0.3048 0.9906)
			(end -0.3048 0.9906)
			(stroke
				(width 0.1)
				(type default)
			)
			(layer "B.Fab")
		)
		(pad "1" smd rect
			(at 0 0 180)
			(size 0.508 0.508)
			(layers "B.Cu" "B.Mask" "B.Paste")
			(net "P3E_CPU0_PE1_PCH_RXN<0>")
		)
		(pad "2" smd rect
			(at 0 0.889 180)
			(size 0.508 0.508)
			(layers "B.Cu" "B.Mask" "B.Paste")
			(net "P3E_CPU0_PE1_SS_RXN<0>")
		)
		(zone
			(layer "B.Cu")
			(hatch none 0.5)
			(connect_pads
				(clearance 0)
			)
			(min_thickness 0.25)
			(keepout
				(tracks allowed)
				(vias not_allowed)
				(pads allowed)
				(copperpour not_allowed)
				(footprints allowed)
			)
			(placement
				(enabled no)
				(sheetname "")
			)
			(fill
				(thermal_gap 0.5)
				(thermal_bridge_width 0.5)
				(island_removal_mode 0)
			)
			(polygon
				(pts
					(xy 334.997806 -61.003434) (xy 334.489806 -61.003434) (xy 334.489806 -60.622434) (xy 334.997806 -60.622434)
				)
			)
		)
		(zone
			(layer "B.Cu")
			(hatch none 0.5)
			(connect_pads
				(clearance 0)
			)
			(min_thickness 0.25)
			(keepout
				(tracks not_allowed)
				(vias allowed)
				(pads allowed)
				(copperpour not_allowed)
				(footprints allowed)
			)
			(placement
				(enabled no)
				(sheetname "")
			)
			(fill
				(thermal_gap 0.5)
				(thermal_bridge_width 0.5)
				(island_removal_mode 0)
			)
			(polygon
				(pts
					(xy 334.997806 -60.622434) (xy 334.489806 -60.622434) (xy 334.489806 -61.003434) (xy 334.997806 -61.003434)
				)
			)
		)
	)
)
